(kicad_pcb
	(version 20241229)
	(generator "pcbnew")
	(generator_version "9.0")
	(general
		(thickness 1.599998)
		(legacy_teardrops no)
	)
	(paper "A4")
	(title_block
		(date "2023-02-12")
		(rev "1.1.5")
		(comment 9 "footprints 245-253 of 473")
	)
	(layers
		(0 "F.Cu" signal)
		(4 "In1.Cu" power "In1.GND")
		(6 "In2.Cu" signal)
		(8 "In3.Cu" power "In3.GND")
		(10 "In4.Cu" power "In4.VCC")
		(12 "In5.Cu" signal)
		(14 "In6.Cu" power "In6.VCC")
		(2 "B.Cu" signal)
		(9 "F.Adhes" user "F.Adhesive")
		(11 "B.Adhes" user "B.Adhesive")
		(13 "F.Paste" user)
		(15 "B.Paste" user)
		(5 "F.SilkS" user "F.Silkscreen")
		(7 "B.SilkS" user "B.Silkscreen")
		(1 "F.Mask" user)
		(3 "B.Mask" user)
		(17 "Dwgs.User" user "User.Drawings")
		(19 "Cmts.User" user "User.Comments")
		(21 "Eco1.User" user "User.Eco1")
		(23 "Eco2.User" user "User.Eco2")
		(25 "Edge.Cuts" user)
		(27 "Margin" user)
		(31 "F.CrtYd" user "F.Courtyard")
		(29 "B.CrtYd" user "B.Courtyard")
		(35 "F.Fab" user)
		(33 "B.Fab" user)
	)
	(footprint "antmicro-footprints:C_0402_1005Metric"
		(layer "F.Cu")
		(at 123.4325 95.249 180)
		(descr "Capacitor SMD 0402")
		(tags "capacitor SMD 0402")
		(property "Reference" "C181"
			(at 1.9325 2.449 180)
			(layer "F.SilkS")
			(effects
				(font
					(size 0.7 0.7)
					(thickness 0.15)
				)
				(justify left bottom)
			)
		)
		(property "Value" "C_1u_0402"
			(at 0 1.4 180)
			(layer "F.Fab")
			(effects
				(font
					(size 0.7 0.7)
					(thickness 0.15)
				)
				(justify left bottom)
			)
		)
		(property "Description" " "
			(at 0 0 180)
			(layer "F.Fab")
			(hide yes)
			(effects
				(font
					(size 1.27 1.27)
					(thickness 0.15)
				)
			)
		)
		(property "Author" "Antmicro"
			(at 246.865 190.498 0)
			(layer "F.Fab")
			(hide yes)
			(effects
				(font
					(size 1 1)
					(thickness 0.15)
				)
			)
		)
		(property "Dielectric" ""
			(at 246.865 190.498 0)
			(layer "F.Fab")
			(hide yes)
			(effects
				(font
					(size 1 1)
					(thickness 0.15)
				)
			)
		)
		(property "License" "Apache-2.0"
			(at 246.865 190.498 0)
			(layer "F.Fab")
			(hide yes)
			(effects
				(font
					(size 1 1)
					(thickness 0.15)
				)
			)
		)
		(property "MPN" "C1005X6S1A105K050BC"
			(at 246.865 190.498 0)
			(layer "F.Fab")
			(hide yes)
			(effects
				(font
					(size 1 1)
					(thickness 0.15)
				)
			)
		)
		(property "Manufacturer" "TDK"
			(at 246.865 190.498 0)
			(layer "F.Fab")
			(hide yes)
			(effects
				(font
					(size 1 1)
					(thickness 0.15)
				)
			)
		)
		(property "Val" "1u"
			(at 246.865 190.498 0)
			(layer "F.Fab")
			(hide yes)
			(effects
				(font
					(size 1 1)
					(thickness 0.15)
				)
			)
		)
		(property "Voltage" ""
			(at 246.865 190.498 0)
			(layer "F.Fab")
			(hide yes)
			(effects
				(font
					(size 1 1)
					(thickness 0.15)
				)
			)
		)
		(sheetname "Supply")
		(sheetfile "supply.kicad_sch")
		(attr smd)
		(fp_rect
			(start -0.94 -0.47)
			(end 0.94 0.47)
			(stroke
				(width 0.05)
				(type solid)
			)
			(fill no)
			(layer "F.CrtYd")
		)
		(fp_rect
			(start -0.499 -0.249)
			(end 0.499 0.249)
			(stroke
				(width 0.15)
				(type solid)
			)
			(fill no)
			(layer "F.Fab")
		)
		(pad "1" smd roundrect
			(at -0.484 0 180)
			(size 0.59 0.64)
			(layers "F.Cu" "F.Mask" "F.Paste")
			(roundrect_rratio 0.25)
			(net 588 "/Supply/1V0_REG")
			(pintype "passive")
		)
		(pad "2" smd roundrect
			(at 0.484 0 180)
			(size 0.59 0.64)
			(layers "F.Cu" "F.Mask" "F.Paste")
			(roundrect_rratio 0.25)
			(net 5 "GND")
			(pintype "passive")
		)
	)
	(footprint "antmicro-footprints:TP_SMD_1mm"
		(layer "F.Cu")
		(at 144.7 92.599 180)
		(property "Reference" "TP18"
			(at 1.4 9.029098 180)
			(layer "F.SilkS")
			(effects
				(font
					(size 0.7 0.7)
					(thickness 0.15)
				)
				(justify left bottom)
			)
		)
		(property "Value" "TP_1mm_SMD"
			(at 0 1.4 180)
			(layer "F.Fab")
			(effects
				(font
					(size 0.7 0.7)
					(thickness 0.15)
				)
				(justify left bottom)
			)
		)
		(property "Description" "Test Point 1mm"
			(at 0 0 180)
			(layer "F.Fab")
			(hide yes)
			(effects
				(font
					(size 1.27 1.27)
					(thickness 0.15)
				)
			)
		)
		(property "Author" "Antmicro"
			(at 289.4 185.198 0)
			(layer "F.Fab")
			(hide yes)
			(effects
				(font
					(size 1 1)
					(thickness 0.15)
				)
			)
		)
		(property "License" "Apache-2.0"
			(at 289.4 185.198 0)
			(layer "F.Fab")
			(hide yes)
			(effects
				(font
					(size 1 1)
					(thickness 0.15)
				)
			)
		)
		(property "MPN" ""
			(at 289.4 185.198 0)
			(layer "F.Fab")
			(hide yes)
			(effects
				(font
					(size 1 1)
					(thickness 0.15)
				)
			)
		)
		(property "Manufacturer" ""
			(at 289.4 185.198 0)
			(layer "F.Fab")
			(hide yes)
			(effects
				(font
					(size 1 1)
					(thickness 0.15)
				)
			)
		)
		(sheetname "Supply")
		(sheetfile "supply.kicad_sch")
		(attr exclude_from_pos_files)
		(pad "1" smd circle
			(at 0 0 180)
			(size 1 1)
			(layers "F.Cu" "F.Mask")
			(net 460 "1V8_SYS")
			(pinfunction "1")
			(pintype "passive")
		)
	)
	(footprint "antmicro-footprints:R_0402_1005Metric"
		(layer "F.Cu")
		(at 114.9492 109 180)
		(descr "Resistor SMD 0402")
		(tags "resistor SMD 0402")
		(property "Reference" "R110"
			(at -0.7508 -0.4 180)
			(layer "F.SilkS")
			(effects
				(font
					(size 0.7 0.7)
					(thickness 0.15)
				)
				(justify left bottom)
			)
		)
		(property "Value" "R_330R_0402"
			(at 0 1.4 180)
			(layer "F.Fab")
			(effects
				(font
					(size 0.7 0.7)
					(thickness 0.15)
				)
				(justify left bottom)
			)
		)
		(property "Description" "330R resistor in 0402 package with 1% tolerance"
			(at 0 0 180)
			(layer "F.Fab")
			(hide yes)
			(effects
				(font
					(size 1.27 1.27)
					(thickness 0.15)
				)
			)
		)
		(property "Author" "Antmicro"
			(at 229.8984 218 0)
			(layer "F.Fab")
			(hide yes)
			(effects
				(font
					(size 1 1)
					(thickness 0.15)
				)
			)
		)
		(property "License" "Apache-2.0"
			(at 229.8984 218 0)
			(layer "F.Fab")
			(hide yes)
			(effects
				(font
					(size 1 1)
					(thickness 0.15)
				)
			)
		)
		(property "MPN" "CR0402-FX-3300GLF"
			(at 229.8984 218 0)
			(layer "F.Fab")
			(hide yes)
			(effects
				(font
					(size 1 1)
					(thickness 0.15)
				)
			)
		)
		(property "Manufacturer" "Bourns"
			(at 229.8984 218 0)
			(layer "F.Fab")
			(hide yes)
			(effects
				(font
					(size 1 1)
					(thickness 0.15)
				)
			)
		)
		(property "Tolerance" "1%"
			(at 229.8984 218 0)
			(layer "F.Fab")
			(hide yes)
			(effects
				(font
					(size 1 1)
					(thickness 0.15)
				)
			)
		)
		(property "Val" "330R"
			(at 229.8984 218 0)
			(layer "F.Fab")
			(hide yes)
			(effects
				(font
					(size 1 1)
					(thickness 0.15)
				)
			)
		)
		(sheetname "Supply")
		(sheetfile "supply.kicad_sch")
		(attr smd)
		(fp_rect
			(start -0.93 -0.47)
			(end 0.93 0.47)
			(stroke
				(width 0.05)
				(type solid)
			)
			(fill no)
			(layer "F.CrtYd")
		)
		(fp_rect
			(start -0.5 -0.25)
			(end 0.5 0.25)
			(stroke
				(width 0.15)
				(type solid)
			)
			(fill no)
			(layer "F.Fab")
		)
		(pad "1" smd roundrect
			(at -0.485 0 180)
			(size 0.59 0.64)
			(layers "F.Cu" "F.Mask" "F.Paste")
			(roundrect_rratio 0.25)
			(net 632 "Net-(PWR6-Pad2)")
			(pintype "passive")
		)
		(pad "2" smd roundrect
			(at 0.485 0 180)
			(size 0.59 0.64)
			(layers "F.Cu" "F.Mask" "F.Paste")
			(roundrect_rratio 0.25)
			(net 5 "GND")
			(pintype "passive")
		)
	)
	(footprint "antmicro-footprints:C_0402_1005Metric"
		(layer "F.Cu")
		(at 184.1 115.135 90)
		(descr "Capacitor SMD 0402")
		(tags "capacitor SMD 0402")
		(property "Reference" "C155"
			(at -3.665 0.4 270)
			(layer "F.SilkS")
			(effects
				(font
					(size 0.7 0.7)
					(thickness 0.15)
				)
				(justify left bottom)
			)
		)
		(property "Value" "C_10u_0402"
			(at 0 1.4 90)
			(layer "F.Fab")
			(effects
				(font
					(size 0.7 0.7)
					(thickness 0.15)
				)
				(justify left bottom)
			)
		)
		(property "Description" " "
			(at 0 0 90)
			(layer "F.Fab")
			(hide yes)
			(effects
				(font
					(size 1.27 1.27)
					(thickness 0.15)
				)
			)
		)
		(property "Author" "Antmicro"
			(at 299.235 -68.965 0)
			(layer "F.Fab")
			(hide yes)
			(effects
				(font
					(size 1 1)
					(thickness 0.15)
				)
			)
		)
		(property "Dielectric" ""
			(at 299.235 -68.965 0)
			(layer "F.Fab")
			(hide yes)
			(effects
				(font
					(size 1 1)
					(thickness 0.15)
				)
			)
		)
		(property "License" "Apache-2.0"
			(at 299.235 -68.965 0)
			(layer "F.Fab")
			(hide yes)
			(effects
				(font
					(size 1 1)
					(thickness 0.15)
				)
			)
		)
		(property "MPN" "CC0402MRX5R5BB106"
			(at 299.235 -68.965 0)
			(layer "F.Fab")
			(hide yes)
			(effects
				(font
					(size 1 1)
					(thickness 0.15)
				)
			)
		)
		(property "Manufacturer" "Yaego"
			(at 299.235 -68.965 0)
			(layer "F.Fab")
			(hide yes)
			(effects
				(font
					(size 1 1)
					(thickness 0.15)
				)
			)
		)
		(property "Val" "10u"
			(at 299.235 -68.965 0)
			(layer "F.Fab")
			(hide yes)
			(effects
				(font
					(size 1 1)
					(thickness 0.15)
				)
			)
		)
		(property "Voltage" ""
			(at 299.235 -68.965 0)
			(layer "F.Fab")
			(hide yes)
			(effects
				(font
					(size 1 1)
					(thickness 0.15)
				)
			)
		)
		(sheetname "Supply")
		(sheetfile "supply.kicad_sch")
		(attr smd)
		(fp_rect
			(start -0.94 -0.47)
			(end 0.94 0.47)
			(stroke
				(width 0.05)
				(type solid)
			)
			(fill no)
			(layer "F.CrtYd")
		)
		(fp_rect
			(start -0.499 -0.249)
			(end 0.499 0.249)
			(stroke
				(width 0.15)
				(type solid)
			)
			(fill no)
			(layer "F.Fab")
		)
		(pad "1" smd roundrect
			(at -0.484 0 90)
			(size 0.59 0.64)
			(layers "F.Cu" "F.Mask" "F.Paste")
			(roundrect_rratio 0.25)
			(net 463 "VCC5V0_INT")
			(pintype "passive")
		)
		(pad "2" smd roundrect
			(at 0.484 0 90)
			(size 0.59 0.64)
			(layers "F.Cu" "F.Mask" "F.Paste")
			(roundrect_rratio 0.25)
			(net 5 "GND")
			(pintype "passive")
		)
	)
	(footprint "antmicro-footprints:DDR5-testbed"
		(layer "F.Cu")
		(at 150.4 60.09 180)
		(property "Reference" "M1"
			(at -0.65 -0.31 180)
			(layer "F.SilkS")
			(hide yes)
			(effects
				(font
					(size 0.7 0.7)
					(thickness 0.15)
				)
				(justify left bottom)
			)
		)
		(property "Value" "ddr5-testbed"
			(at -3.2 0.4 180)
			(layer "F.Fab")
			(effects
				(font
					(size 0.7 0.7)
					(thickness 0.15)
				)
				(justify left bottom)
			)
		)
		(property "Description" "DDR5 testbed"
			(at 0 0 180)
			(layer "F.Fab")
			(hide yes)
			(effects
				(font
					(size 1.27 1.27)
					(thickness 0.15)
				)
			)
		)
		(property "Author" "Antmicro"
			(at 300.8 120.18 0)
			(layer "F.Fab")
			(hide yes)
			(effects
				(font
					(size 1 1)
					(thickness 0.15)
				)
			)
		)
		(property "License" "Apache-2.0"
			(at 300.8 120.18 0)
			(layer "F.Fab")
			(hide yes)
			(effects
				(font
					(size 1 1)
					(thickness 0.15)
				)
			)
		)
		(property "MPN" ""
			(at 300.8 120.18 0)
			(layer "F.Fab")
			(hide yes)
			(effects
				(font
					(size 1 1)
					(thickness 0.15)
				)
			)
		)
		(property "Manufacturer" "Antmicro "
			(at 300.8 120.18 0)
			(layer "F.Fab")
			(hide yes)
			(effects
				(font
					(size 1 1)
					(thickness 0.15)
				)
			)
		)
		(sheetname "SO-DIMM")
		(sheetfile "sodimm.kicad_sch")
		(attr exclude_from_pos_files exclude_from_bom dnp)
		(fp_rect
			(start -35 -15.151)
			(end 34.999 15.349)
			(stroke
				(width 0.15)
				(type solid)
			)
			(fill no)
			(layer "F.Fab")
		)
	)
	(footprint "antmicro-footprints:R_0402_1005Metric"
		(layer "F.Cu")
		(at 123.6475 101.449 180)
		(descr "Resistor SMD 0402")
		(tags "resistor SMD 0402")
		(property "Reference" "R143"
			(at 3.5475 -0.351 180)
			(layer "F.SilkS")
			(effects
				(font
					(size 0.7 0.7)
					(thickness 0.15)
				)
				(justify left bottom)
			)
		)
		(property "Value" "R_10k_0402"
			(at 0 1.4 180)
			(layer "F.Fab")
			(effects
				(font
					(size 0.7 0.7)
					(thickness 0.15)
				)
				(justify left bottom)
			)
		)
		(property "Description" "10k resistor in 0402 package with 1% tolerance"
			(at 0 0 180)
			(layer "F.Fab")
			(hide yes)
			(effects
				(font
					(size 1.27 1.27)
					(thickness 0.15)
				)
			)
		)
		(property "Author" "Antmicro"
			(at 247.295 202.898 0)
			(layer "F.Fab")
			(hide yes)
			(effects
				(font
					(size 1 1)
					(thickness 0.15)
				)
			)
		)
		(property "License" "Apache-2.0"
			(at 247.295 202.898 0)
			(layer "F.Fab")
			(hide yes)
			(effects
				(font
					(size 1 1)
					(thickness 0.15)
				)
			)
		)
		(property "MPN" "CR0402-FX-1002GLF"
			(at 247.295 202.898 0)
			(layer "F.Fab")
			(hide yes)
			(effects
				(font
					(size 1 1)
					(thickness 0.15)
				)
			)
		)
		(property "Manufacturer" "Bourns"
			(at 247.295 202.898 0)
			(layer "F.Fab")
			(hide yes)
			(effects
				(font
					(size 1 1)
					(thickness 0.15)
				)
			)
		)
		(property "Tolerance" "1%"
			(at 247.295 202.898 0)
			(layer "F.Fab")
			(hide yes)
			(effects
				(font
					(size 1 1)
					(thickness 0.15)
				)
			)
		)
		(property "Val" "10k"
			(at 247.295 202.898 0)
			(layer "F.Fab")
			(hide yes)
			(effects
				(font
					(size 1 1)
					(thickness 0.15)
				)
			)
		)
		(sheetname "Supply")
		(sheetfile "supply.kicad_sch")
		(attr smd)
		(fp_rect
			(start -0.93 -0.47)
			(end 0.93 0.47)
			(stroke
				(width 0.05)
				(type solid)
			)
			(fill no)
			(layer "F.CrtYd")
		)
		(fp_rect
			(start -0.5 -0.25)
			(end 0.5 0.25)
			(stroke
				(width 0.15)
				(type solid)
			)
			(fill no)
			(layer "F.Fab")
		)
		(pad "1" smd roundrect
			(at -0.485 0 180)
			(size 0.59 0.64)
			(layers "F.Cu" "F.Mask" "F.Paste")
			(roundrect_rratio 0.25)
			(net 599 "/Supply/1V0_FB")
			(pintype "passive")
		)
		(pad "2" smd roundrect
			(at 0.485 0 180)
			(size 0.59 0.64)
			(layers "F.Cu" "F.Mask" "F.Paste")
			(roundrect_rratio 0.25)
			(net 5 "GND")
			(pintype "passive")
		)
	)
	(footprint "antmicro-footprints:TP_SMD_1mm"
		(layer "F.Cu")
		(at 171.1 112.1508)
		(property "Reference" "TP7"
			(at -2.5 0.4492 0)
			(layer "F.SilkS")
			(effects
				(font
					(size 0.7 0.7)
					(thickness 0.15)
				)
				(justify left bottom)
			)
		)
		(property "Value" "TP_1mm_SMD"
			(at 0 1.4 0)
			(layer "F.Fab")
			(effects
				(font
					(size 0.7 0.7)
					(thickness 0.15)
				)
				(justify left bottom)
			)
		)
		(property "Description" "Test Point 1mm"
			(at 0 0 0)
			(layer "F.Fab")
			(hide yes)
			(effects
				(font
					(size 1.27 1.27)
					(thickness 0.15)
				)
			)
		)
		(property "Author" "Antmicro"
			(at 0 0 0)
			(layer "F.Fab")
			(hide yes)
			(effects
				(font
					(size 1 1)
					(thickness 0.15)
				)
			)
		)
		(property "License" "Apache-2.0"
			(at 0 0 0)
			(layer "F.Fab")
			(hide yes)
			(effects
				(font
					(size 1 1)
					(thickness 0.15)
				)
			)
		)
		(property "MPN" ""
			(at 0 0 0)
			(layer "F.Fab")
			(hide yes)
			(effects
				(font
					(size 1 1)
					(thickness 0.15)
				)
			)
		)
		(property "Manufacturer" ""
			(at 0 0 0)
			(layer "F.Fab")
			(hide yes)
			(effects
				(font
					(size 1 1)
					(thickness 0.15)
				)
			)
		)
		(sheetname "Config SPI flash")
		(sheetfile "config-spi.kicad_sch")
		(attr exclude_from_pos_files)
		(pad "1" smd circle
			(at 0 0)
			(size 1 1)
			(layers "F.Cu" "F.Mask")
			(net 95 "PUDC_B")
			(pinfunction "1")
			(pintype "passive")
		)
	)
	(footprint "antmicro-footprints:C_0603_1608Metric"
		(layer "F.Cu")
		(at 125.3 61.475 180)
		(descr "Capacitor SMD 0603")
		(tags "capacitor 0603")
		(property "Reference" "C182"
			(at 3.9 -0.35 180)
			(layer "F.SilkS")
			(effects
				(font
					(size 0.7 0.7)
					(thickness 0.15)
				)
				(justify left bottom)
			)
		)
		(property "Value" "C_10u_0603"
			(at 0 1.6 180)
			(layer "F.Fab")
			(effects
				(font
					(size 0.7 0.7)
					(thickness 0.15)
				)
				(justify left bottom)
			)
		)
		(property "Description" " "
			(at 0 0 180)
			(layer "F.Fab")
			(hide yes)
			(effects
				(font
					(size 1.27 1.27)
					(thickness 0.15)
				)
			)
		)
		(property "Author" "Antmicro"
			(at 250.6 122.95 0)
			(layer "F.Fab")
			(hide yes)
			(effects
				(font
					(size 1 1)
					(thickness 0.15)
				)
			)
		)
		(property "License" "Apache-2.0"
			(at 250.6 122.95 0)
			(layer "F.Fab")
			(hide yes)
			(effects
				(font
					(size 1 1)
					(thickness 0.15)
				)
			)
		)
		(property "MPN" "GRM188R61A106KE69D"
			(at 250.6 122.95 0)
			(layer "F.Fab")
			(hide yes)
			(effects
				(font
					(size 1 1)
					(thickness 0.15)
				)
			)
		)
		(property "Manufacturer" "Murata"
			(at 250.6 122.95 0)
			(layer "F.Fab")
			(hide yes)
			(effects
				(font
					(size 1 1)
					(thickness 0.15)
				)
			)
		)
		(property "Val" "10u"
			(at 250.6 122.95 0)
			(layer "F.Fab")
			(hide yes)
			(effects
				(font
					(size 1 1)
					(thickness 0.15)
				)
			)
		)
		(property "Voltage" ""
			(at 250.6 122.95 0)
			(layer "F.Fab")
			(hide yes)
			(effects
				(font
					(size 1 1)
					(thickness 0.15)
				)
			)
		)
		(sheetname "Supply")
		(sheetfile "supply.kicad_sch")
		(attr exclude_from_pos_files exclude_from_bom dnp)
		(fp_line
			(start -0.3 0.3)
			(end 0.3 0.3)
			(stroke
				(width 0.15)
				(type solid)
			)
			(layer "F.SilkS")
		)
		(fp_line
			(start -0.3 -0.3)
			(end 0.3 -0.3)
			(stroke
				(width 0.15)
				(type solid)
			)
			(layer "F.SilkS")
		)
		(fp_rect
			(start -1.24 -0.7)
			(end 1.24 0.7)
			(stroke
				(width 0.05)
				(type solid)
			)
			(fill no)
			(layer "F.CrtYd")
		)
		(fp_rect
			(start -0.8 -0.4)
			(end 0.8 0.4)
			(stroke
				(width 0.15)
				(type solid)
			)
			(fill no)
			(layer "F.Fab")
		)
		(pad "1" smd roundrect
			(at -0.7 0 180)
			(size 0.6 0.8)
			(layers "F.Cu" "F.Mask" "F.Paste")
			(roundrect_rratio 0.2)
			(net 463 "VCC5V0_INT")
			(pintype "passive")
		)
		(pad "2" smd roundrect
			(at 0.7 0 180)
			(size 0.6 0.8)
			(layers "F.Cu" "F.Mask" "F.Paste")
			(roundrect_rratio 0.2)
			(net 5 "GND")
			(pintype "passive")
		)
	)
	(footprint "antmicro-footprints:R_0402_1005Metric"
		(layer "F.Cu")
		(at 109.2492 115.7)
		(descr "Resistor SMD 0402")
		(tags "resistor SMD 0402")
		(property "Reference" "R166"
			(at -1.9492 -0.5 0)
			(layer "F.SilkS")
			(effects
				(font
					(size 0.7 0.7)
					(thickness 0.15)
				)
				(justify left bottom)
			)
		)
		(property "Value" "R_243k_0402"
			(at 0 1.4 0)
			(layer "F.Fab")
			(effects
				(font
					(size 0.7 0.7)
					(thickness 0.15)
				)
				(justify left bottom)
			)
		)
		(property "Description" "243k resistor in 0402 package with 1% tolerance"
			(at 0 0 0)
			(layer "F.Fab")
			(hide yes)
			(effects
				(font
					(size 1.27 1.27)
					(thickness 0.15)
				)
			)
		)
		(property "Author" "Antmicro"
			(at 0 0 0)
			(layer "F.Fab")
			(hide yes)
			(effects
				(font
					(size 1 1)
					(thickness 0.15)
				)
			)
		)
		(property "License" "Apache-2.0"
			(at 0 0 0)
			(layer "F.Fab")
			(hide yes)
			(effects
				(font
					(size 1 1)
					(thickness 0.15)
				)
			)
		)
		(property "MPN" "CR0402-FX-2433GLF"
			(at 0 0 0)
			(layer "F.Fab")
			(hide yes)
			(effects
				(font
					(size 1 1)
					(thickness 0.15)
				)
			)
		)
		(property "Manufacturer" "Bourns"
			(at 0 0 0)
			(layer "F.Fab")
			(hide yes)
			(effects
				(font
					(size 1 1)
					(thickness 0.15)
				)
			)
		)
		(property "Tolerance" "1%"
			(at 0 0 0)
			(layer "F.Fab")
			(hide yes)
			(effects
				(font
					(size 1 1)
					(thickness 0.15)
				)
			)
		)
		(property "Val" "243k"
			(at 0 0 0)
			(layer "F.Fab")
			(hide yes)
			(effects
				(font
					(size 1 1)
					(thickness 0.15)
				)
			)
		)
		(sheetname "Supply")
		(sheetfile "supply.kicad_sch")
		(attr smd)
		(fp_rect
			(start -0.93 -0.47)
			(end 0.93 0.47)
			(stroke
				(width 0.05)
				(type solid)
			)
			(fill no)
			(layer "F.CrtYd")
		)
		(fp_rect
			(start -0.5 -0.25)
			(end 0.5 0.25)
			(stroke
				(width 0.15)
				(type solid)
			)
			(fill no)
			(layer "F.Fab")
		)
		(pad "1" smd roundrect
			(at -0.485 0)
			(size 0.59 0.64)
			(layers "F.Cu" "F.Mask" "F.Paste")
			(roundrect_rratio 0.25)
			(net 224 "VIN")
			(pintype "passive")
		)
		(pad "2" smd roundrect
			(at 0.485 0)
			(size 0.59 0.64)
			(layers "F.Cu" "F.Mask" "F.Paste")
			(roundrect_rratio 0.25)
			(net 514 "/Supply/SYS_EN")
			(pintype "passive")
		)
	)
)
